# T6G (Grand Teton) — schematic netlist excerpt (pin names and nets, part order shuffled) for the footprints in the layout excerpt that follows; sources: Cadence DE-HDL packaged netlist, KiCad conversion of 04192023_DAF0TMB3IC0_F0TG_MB_C_brd_V02_OCP.brd

R1207  Q_RES  470 1% CHIP  pkg 0402LF  page 166 : A = P5V_STBY_PWR_LED ; B = P5V_AUX
C8072  Q_CAP  1000PF 50V 5% EMPTY  pkg 0402  page 200 : A = PWRGD_PVDDIO_P0_R ; B = GND

(kicad_pcb
	(version 20260206)
	(generator "pcbnew")
	(generator_version "10.0")
	(general
		(thickness 1.6)
		(legacy_teardrops no)
	)
	(paper "A4")
	(title_block
		(title "04192023_DAF0TMB3IC0_F0TG_MB_C_brd_V02_OCP.brd")
		(comment 1 "Grand Teton / footprints 3145-3146 of 8354")
	)
	(layers
		(0 "F.Cu" signal "TOP")
		(4 "In1.Cu" signal "GND")
		(6 "In2.Cu" signal "IN1")
		(8 "In3.Cu" signal "GND1")
		(10 "In4.Cu" signal "IN2")
		(12 "In5.Cu" signal "GND2")
		(14 "In6.Cu" signal "IN3")
		(16 "In7.Cu" signal "GND3")
		(18 "In8.Cu" signal "VCC")
		(20 "In9.Cu" signal "VCC1")
		(22 "In10.Cu" signal "GND4")
		(24 "In11.Cu" signal "IN4")
		(26 "In12.Cu" signal "GND5")
		(28 "In13.Cu" signal "IN5")
		(30 "In14.Cu" signal "GND6")
		(32 "In15.Cu" signal "IN6")
		(34 "In16.Cu" signal "GND7")
		(2 "B.Cu" signal "BOTTOM")
		(9 "F.Adhes" user "F.Adhesive")
		(11 "B.Adhes" user "B.Adhesive")
		(13 "F.Paste" user "Package Geometry/Pastemask Top")
		(15 "B.Paste" user "Package Geometry/Pastemask Bottom")
		(5 "F.SilkS" user "Ref Des/Silkscreen Top")
		(7 "B.SilkS" user "Ref Des/Silkscreen Bottom")
		(1 "F.Mask" user "Board Geometry/Soldermask Top")
		(3 "B.Mask" user "Board Geometry/Soldermask Bottom")
		(17 "Dwgs.User" user "User.Drawings")
		(19 "Cmts.User" user "User.Comments")
		(21 "Eco1.User" user "User.Eco1")
		(23 "Eco2.User" user "User.Eco2")
		(25 "Edge.Cuts" user "Board Geometry/Outline")
		(27 "Margin" user)
		(31 "F.CrtYd" user "Package Geometry/Place Bound Top")
		(29 "B.CrtYd" user "Package Geometry/Place Bound Bottom")
		(35 "F.Fab" user "Ref Des/Assembly Top")
		(33 "B.Fab" user "Ref Des/Assembly Bottom")
	)
	(footprint ""
		(layer "F.Cu")
		(at 344.3605 -15.979394 90)
		(property "Reference" "R1207"
			(at 0 0 90)
			(layer "F.SilkS")
			(hide yes)
			(effects
				(font
					(size 1.27 1.27)
				)
			)
		)
		(property "Value" ""
			(at 0 0 90)
			(layer "F.Fab")
			(effects
				(font
					(size 1.27 1.27)
				)
			)
		)
		(duplicate_pad_numbers_are_jumpers no)
		(fp_line
			(start 0.7874 -0.4064)
			(end 0.7874 0.4064)
			(stroke
				(width 0.1524)
				(type default)
			)
			(layer "F.SilkS")
		)
		(fp_line
			(start -0.7874 -0.4064)
			(end 0.7874 -0.4064)
			(stroke
				(width 0.1524)
				(type default)
			)
			(layer "F.SilkS")
		)
		(fp_line
			(start 0.7874 0.4064)
			(end -0.7874 0.4064)
			(stroke
				(width 0.1524)
				(type default)
			)
			(layer "F.SilkS")
		)
		(fp_line
			(start -0.7874 0.4064)
			(end -0.7874 -0.4064)
			(stroke
				(width 0.1524)
				(type default)
			)
			(layer "F.SilkS")
		)
		(fp_line
			(start -0.12065 -0.305054)
			(end -0.12065 -0.2794)
			(stroke
				(width 0.1)
				(type default)
			)
			(layer "F.Fab")
		)
		(fp_line
			(start -0.67945 -0.305054)
			(end -0.12065 -0.305054)
			(stroke
				(width 0.1)
				(type default)
			)
			(layer "F.Fab")
		)
		(fp_line
			(start 0.67945 -0.3048)
			(end 0.67945 0.3048)
			(stroke
				(width 0.1)
				(type default)
			)
			(layer "F.Fab")
		)
		(fp_line
			(start 0.12065 -0.3048)
			(end 0.67945 -0.3048)
			(stroke
				(width 0.1)
				(type default)
			)
			(layer "F.Fab")
		)
		(fp_line
			(start 0.12065 -0.2794)
			(end 0.12065 -0.3048)
			(stroke
				(width 0.1)
				(type default)
			)
			(layer "F.Fab")
		)
		(fp_line
			(start -0.12065 -0.2794)
			(end 0.12065 -0.2794)
			(stroke
				(width 0.1)
				(type default)
			)
			(layer "F.Fab")
		)
		(fp_line
			(start 0.120396 0.2794)
			(end -0.12065 0.2794)
			(stroke
				(width 0.1)
				(type default)
			)
			(layer "F.Fab")
		)
		(fp_line
			(start -0.12065 0.2794)
			(end -0.12065 0.3048)
			(stroke
				(width 0.1)
				(type default)
			)
			(layer "F.Fab")
		)
		(fp_line
			(start 0.67945 0.3048)
			(end 0.120396 0.3048)
			(stroke
				(width 0.1)
				(type default)
			)
			(layer "F.Fab")
		)
		(fp_line
			(start 0.120396 0.3048)
			(end 0.120396 0.2794)
			(stroke
				(width 0.1)
				(type default)
			)
			(layer "F.Fab")
		)
		(fp_line
			(start -0.12065 0.3048)
			(end -0.67945 0.3048)
			(stroke
				(width 0.1)
				(type default)
			)
			(layer "F.Fab")
		)
		(fp_line
			(start -0.67945 0.3048)
			(end -0.67945 -0.305054)
			(stroke
				(width 0.1)
				(type default)
			)
			(layer "F.Fab")
		)
		(pad "1" smd circle
			(at -0.40005 0 90)
			(size 0 0)
			(layers "F.Cu" "F.Mask" "F.Paste")
			(net "P5V_STBY_PWR_LED")
		)
		(pad "2" smd circle
			(at 0.40005 0 90)
			(size 0 0)
			(layers "F.Cu" "F.Mask" "F.Paste")
			(net "P5V_AUX")
		)
	)
	(footprint ""
		(layer "F.Cu")
		(at 304.419 -359.283 180)
		(property "Reference" "C8072"
			(at 0 0 180)
			(layer "F.SilkS")
			(hide yes)
			(effects
				(font
					(size 1.27 1.27)
				)
			)
		)
		(property "Value" ""
			(at 0 0 180)
			(layer "F.Fab")
			(effects
				(font
					(size 1.27 1.27)
				)
			)
		)
		(duplicate_pad_numbers_are_jumpers no)
		(fp_line
			(start 0.7874 0.4064)
			(end -0.7874 0.4064)
			(stroke
				(width 0.1524)
				(type default)
			)
			(layer "F.SilkS")
		)
		(fp_line
			(start 0.7874 -0.4064)
			(end 0.7874 0.4064)
			(stroke
				(width 0.1524)
				(type default)
			)
			(layer "F.SilkS")
		)
		(fp_line
			(start -0.7874 0.4064)
			(end -0.7874 -0.4064)
			(stroke
				(width 0.1524)
				(type default)
			)
			(layer "F.SilkS")
		)
		(fp_line
			(start -0.7874 -0.4064)
			(end 0.7874 -0.4064)
			(stroke
				(width 0.1524)
				(type default)
			)
			(layer "F.SilkS")
		)
		(fp_line
			(start 0.67945 0.3048)
			(end 0.120396 0.3048)
			(stroke
				(width 0.1)
				(type default)
			)
			(layer "F.Fab")
		)
		(fp_line
			(start 0.67945 -0.3048)
			(end 0.67945 0.3048)
			(stroke
				(width 0.1)
				(type default)
			)
			(layer "F.Fab")
		)
		(fp_line
			(start 0.12065 -0.2794)
			(end 0.12065 -0.3048)
			(stroke
				(width 0.1)
				(type default)
			)
			(layer "F.Fab")
		)
		(fp_line
			(start 0.12065 -0.3048)
			(end 0.67945 -0.3048)
			(stroke
				(width 0.1)
				(type default)
			)
			(layer "F.Fab")
		)
		(fp_line
			(start 0.120396 0.3048)
			(end 0.120396 0.2794)
			(stroke
				(width 0.1)
				(type default)
			)
			(layer "F.Fab")
		)
		(fp_line
			(start 0.120396 0.2794)
			(end -0.12065 0.2794)
			(stroke
				(width 0.1)
				(type default)
			)
			(layer "F.Fab")
		)
		(fp_line
			(start -0.12065 0.3048)
			(end -0.67945 0.3048)
			(stroke
				(width 0.1)
				(type default)
			)
			(layer "F.Fab")
		)
		(fp_line
			(start -0.12065 0.2794)
			(end -0.12065 0.3048)
			(stroke
				(width 0.1)
				(type default)
			)
			(layer "F.Fab")
		)
		(fp_line
			(start -0.12065 -0.2794)
			(end 0.12065 -0.2794)
			(stroke
				(width 0.1)
				(type default)
			)
			(layer "F.Fab")
		)
		(fp_line
			(start -0.12065 -0.305054)
			(end -0.12065 -0.2794)
			(stroke
				(width 0.1)
				(type default)
			)
			(layer "F.Fab")
		)
		(fp_line
			(start -0.67945 0.3048)
			(end -0.67945 -0.305054)
			(stroke
				(width 0.1)
				(type default)
			)
			(layer "F.Fab")
		)
		(fp_line
			(start -0.67945 -0.305054)
			(end -0.12065 -0.305054)
			(stroke
				(width 0.1)
				(type default)
			)
			(layer "F.Fab")
		)
		(pad "1" smd circle
			(at -0.40005 0 180)
			(size 0 0)
			(layers "F.Cu" "F.Mask" "F.Paste")
			(net "PWRGD_PVDDIO_P0_R")
		)
		(pad "2" smd circle
			(at 0.40005 0 180)
			(size 0 0)
			(layers "F.Cu" "F.Mask" "F.Paste")
			(net "GND")
		)
	)
)
